FILE_TYPE=LIBRARY_PARTS;
primitive '0R3J-0-U-GP_RCL_GP';
  pin
    '1':
      PIN_NUMBER='(1)';
      PIN_TYPE='ANALOG';
      NO_LOAD_CHECK='Both';
      NO_IO_CHECK='Both';
      NO_ASSERT_CHECK='TRUE';
      NO_DIR_CHECK='TRUE';
      ALLOW_CONNECT='TRUE';
    '2':
      PIN_NUMBER='(2)';
      PIN_TYPE='ANALOG';
      NO_LOAD_CHECK='Both';
      NO_IO_CHECK='Both';
      NO_ASSERT_CHECK='TRUE';
      NO_DIR_CHECK='TRUE';
      ALLOW_CONNECT='TRUE';
  end_pin;
  body
    PART_NAME='0R3J-0-U-GP';
    BODY_NAME='0R3J-0-U-GP';
    PHYS_DES_PREFIX='R';
    CLASS='DISCRETE';
  end_body;
end_primitive;

END.
